# BASEBOARD_FAB2 (Tioga Pass) — schematic netlist excerpt (pin names and nets, part order shuffled) for the footprints in the layout excerpt that follows; sources: Cadence DE-HDL packaged netlist, KiCad conversion of Wiwynn_Tioga_Pass_MB.brd

C9U6  CAP  10UF 16V 10% X6S  pkg 0805  page 224 : A = VR_FET_SW_P12V_STBY_PVDDQ_GHJ ; B = GND
R9P27  RES  10.0 1% CHIP  pkg 0402  page 200 : A = P12V_HSC_SENP1 ; B = A_HSC_HSP
C9T8  CAP  10UF 16V 10% X7R  pkg 0805  page 197 : A = P12V_NVDIMM_GHJ ; B = GND

(kicad_pcb
	(version 20260206)
	(generator "pcbnew")
	(generator_version "10.0")
	(general
		(thickness 1.6)
		(legacy_teardrops no)
	)
	(paper "A4")
	(title_block
		(title "Wiwynn_Tioga_Pass_MB.brd")
		(comment 1 "Tioga Pass / footprints 3783-3785 of 4770")
	)
	(layers
		(0 "F.Cu" signal "TOP")
		(4 "In1.Cu" signal "L2GND")
		(6 "In2.Cu" signal "L3")
		(8 "In3.Cu" signal "L4GND")
		(10 "In4.Cu" signal "L5")
		(12 "In5.Cu" signal "L6GND")
		(14 "In6.Cu" signal "L7VCC")
		(16 "In7.Cu" signal "L8VCC")
		(18 "In8.Cu" signal "L9GND")
		(20 "In9.Cu" signal "L10")
		(22 "In10.Cu" signal "L11GND")
		(24 "In11.Cu" signal "L12")
		(26 "In12.Cu" signal "L13GND")
		(2 "B.Cu" signal "BOTTOM")
		(9 "F.Adhes" user "F.Adhesive")
		(11 "B.Adhes" user "B.Adhesive")
		(13 "F.Paste" user "Package Geometry/Pastemask Top")
		(15 "B.Paste" user "Package Geometry/Pastemask Bottom")
		(5 "F.SilkS" user "Ref Des/Silkscreen Top")
		(7 "B.SilkS" user "Ref Des/Silkscreen Bottom")
		(1 "F.Mask" user "Board Geometry/Soldermask Top")
		(3 "B.Mask" user "Board Geometry/Soldermask Bottom")
		(17 "Dwgs.User" user "User.Drawings")
		(19 "Cmts.User" user "User.Comments")
		(21 "Eco1.User" user "User.Eco1")
		(23 "Eco2.User" user "User.Eco2")
		(25 "Edge.Cuts" user "Board Geometry/Outline")
		(27 "Margin" user)
		(31 "F.CrtYd" user "Package Geometry/Place Bound Top")
		(29 "B.CrtYd" user "Package Geometry/Place Bound Bottom")
		(35 "F.Fab" user "Ref Des/Assembly Top")
		(33 "B.Fab" user "Ref Des/Assembly Bottom")
	)
	(footprint ""
		(layer "B.Cu")
		(at 3.8227 -7.727696 90)
		(property "Reference" "C9U6"
			(at 0 0 90)
			(layer "B.SilkS")
			(hide yes)
			(effects
				(font
					(size 1.27 1.27)
				)
				(justify mirror)
			)
		)
		(property "Value" ""
			(at 0 0 90)
			(layer "B.Fab")
			(effects
				(font
					(size 1.27 1.27)
				)
				(justify mirror)
			)
		)
		(duplicate_pad_numbers_are_jumpers no)
		(fp_rect
			(start -0.7239 -0.2159)
			(end 0.7239 1.9939)
			(stroke
				(width 0)
				(type default)
			)
			(fill no)
			(layer "B.CrtYd")
		)
		(fp_line
			(start 0.7239 -0.2159)
			(end 0.7239 1.9939)
			(stroke
				(width 0.1)
				(type default)
			)
			(layer "B.Fab")
		)
		(fp_line
			(start -0.7239 -0.2159)
			(end 0.7239 -0.2159)
			(stroke
				(width 0.1)
				(type default)
			)
			(layer "B.Fab")
		)
		(fp_line
			(start 0.7239 1.9939)
			(end -0.7239 1.9939)
			(stroke
				(width 0.1)
				(type default)
			)
			(layer "B.Fab")
		)
		(fp_line
			(start -0.7239 1.9939)
			(end -0.7239 -0.2159)
			(stroke
				(width 0.1)
				(type default)
			)
			(layer "B.Fab")
		)
		(pad "1" smd rect
			(at 0 0 270)
			(size 1.27 1.016)
			(layers "B.Cu" "B.Mask" "B.Paste")
			(net "VR_FET_SW_P12V_STBY_PVDDQ_GHJ")
		)
		(pad "2" smd rect
			(at 0 1.778 270)
			(size 1.27 1.016)
			(layers "B.Cu" "B.Mask" "B.Paste")
			(net "GND")
		)
		(zone
			(layer "B.Cu")
			(hatch none 0.5)
			(connect_pads
				(clearance 0)
			)
			(min_thickness 0.25)
			(keepout
				(tracks not_allowed)
				(vias allowed)
				(pads allowed)
				(copperpour not_allowed)
				(footprints allowed)
			)
			(placement
				(enabled no)
				(sheetname "")
			)
			(fill
				(thermal_gap 0.5)
				(thermal_bridge_width 0.5)
				(island_removal_mode 0)
			)
			(polygon
				(pts
					(xy 4.3307 -7.092696) (xy 5.0927 -7.092696) (xy 5.0927 -8.362696) (xy 4.3307 -8.362696)
				)
			)
		)
	)
	(footprint ""
		(layer "B.Cu")
		(at 28.0924 -17.723612 -90)
		(property "Reference" "C9T8"
			(at 0 0 90)
			(layer "B.SilkS")
			(hide yes)
			(effects
				(font
					(size 1.27 1.27)
				)
				(justify mirror)
			)
		)
		(property "Value" ""
			(at 0 0 90)
			(layer "B.Fab")
			(effects
				(font
					(size 1.27 1.27)
				)
				(justify mirror)
			)
		)
		(duplicate_pad_numbers_are_jumpers no)
		(fp_rect
			(start 0.7239 -0.2159)
			(end -0.7239 1.9939)
			(stroke
				(width 0)
				(type default)
			)
			(fill no)
			(layer "B.CrtYd")
		)
		(fp_line
			(start -0.7239 1.9939)
			(end -0.7239 -0.2159)
			(stroke
				(width 0.1)
				(type default)
			)
			(layer "B.Fab")
		)
		(fp_line
			(start 0.7239 1.9939)
			(end -0.7239 1.9939)
			(stroke
				(width 0.1)
				(type default)
			)
			(layer "B.Fab")
		)
		(fp_line
			(start -0.7239 -0.2159)
			(end 0.7239 -0.2159)
			(stroke
				(width 0.1)
				(type default)
			)
			(layer "B.Fab")
		)
		(fp_line
			(start 0.7239 -0.2159)
			(end 0.7239 1.9939)
			(stroke
				(width 0.1)
				(type default)
			)
			(layer "B.Fab")
		)
		(pad "1" smd rect
			(at 0 0 90)
			(size 1.27 1.016)
			(layers "B.Cu" "B.Mask" "B.Paste")
			(net "P12V_NVDIMM_GHJ")
		)
		(pad "2" smd rect
			(at 0 1.778 90)
			(size 1.27 1.016)
			(layers "B.Cu" "B.Mask" "B.Paste")
			(net "GND")
		)
		(zone
			(layer "B.Cu")
			(hatch none 0.5)
			(connect_pads
				(clearance 0)
			)
			(min_thickness 0.25)
			(keepout
				(tracks not_allowed)
				(vias allowed)
				(pads allowed)
				(copperpour not_allowed)
				(footprints allowed)
			)
			(placement
				(enabled no)
				(sheetname "")
			)
			(fill
				(thermal_gap 0.5)
				(thermal_bridge_width 0.5)
				(island_removal_mode 0)
			)
			(polygon
				(pts
					(xy 27.5844 -17.088612) (xy 27.5844 -18.358612) (xy 26.8224 -18.358612) (xy 26.8224 -17.088612)
				)
			)
		)
	)
	(footprint ""
		(layer "B.Cu")
		(at 9.398 -68.0466 180)
		(property "Reference" "R9P27"
			(at 0 0 0)
			(layer "B.SilkS")
			(hide yes)
			(effects
				(font
					(size 1.27 1.27)
				)
				(justify mirror)
			)
		)
		(property "Value" ""
			(at 0 0 0)
			(layer "B.Fab")
			(effects
				(font
					(size 1.27 1.27)
				)
				(justify mirror)
			)
		)
		(duplicate_pad_numbers_are_jumpers no)
		(fp_rect
			(start -0.2794 0.9906)
			(end 0.2794 -0.1016)
			(stroke
				(width 0)
				(type default)
			)
			(fill no)
			(layer "B.CrtYd")
		)
		(fp_line
			(start 0.2794 0.9906)
			(end -0.2794 0.9906)
			(stroke
				(width 0.1)
				(type default)
			)
			(layer "B.Fab")
		)
		(fp_line
			(start 0.2794 -0.1016)
			(end 0.2794 0.9906)
			(stroke
				(width 0.1)
				(type default)
			)
			(layer "B.Fab")
		)
		(fp_line
			(start -0.2794 0.9906)
			(end -0.2794 -0.1016)
			(stroke
				(width 0.1)
				(type default)
			)
			(layer "B.Fab")
		)
		(fp_line
			(start -0.2794 -0.1016)
			(end 0.2794 -0.1016)
			(stroke
				(width 0.1)
				(type default)
			)
			(layer "B.Fab")
		)
		(pad "1" smd rect
			(at 0 0)
			(size 0.508 0.508)
			(layers "B.Cu" "B.Mask" "B.Paste")
			(net "P12V_HSC_SENP1")
		)
		(pad "2" smd rect
			(at 0 0.889)
			(size 0.508 0.508)
			(layers "B.Cu" "B.Mask" "B.Paste")
			(net "A_HSC_HSP")
		)
		(zone
			(layer "B.Cu")
			(hatch none 0.5)
			(connect_pads
				(clearance 0)
			)
			(min_thickness 0.25)
			(keepout
				(tracks allowed)
				(vias not_allowed)
				(pads allowed)
				(copperpour not_allowed)
				(footprints allowed)
			)
			(placement
				(enabled no)
				(sheetname "")
			)
			(fill
				(thermal_gap 0.5)
				(thermal_bridge_width 0.5)
				(island_removal_mode 0)
			)
			(polygon
				(pts
					(xy 9.652 -68.6816) (xy 9.144 -68.6816) (xy 9.144 -68.3006) (xy 9.652 -68.3006)
				)
			)
		)
		(zone
			(layer "B.Cu")
			(hatch none 0.5)
			(connect_pads
				(clearance 0)
			)
			(min_thickness 0.25)
			(keepout
				(tracks not_allowed)
				(vias allowed)
				(pads allowed)
				(copperpour not_allowed)
				(footprints allowed)
			)
			(placement
				(enabled no)
				(sheetname "")
			)
			(fill
				(thermal_gap 0.5)
				(thermal_bridge_width 0.5)
				(island_removal_mode 0)
			)
			(polygon
				(pts
					(xy 9.652 -68.6816) (xy 9.144 -68.6816) (xy 9.144 -68.3006) (xy 9.652 -68.3006)
				)
			)
		)
	)
)
